# T6G (Grand Teton) — schematic netlist excerpt (pin names and nets, part order shuffled) for the footprints in the layout excerpt that follows; sources: Cadence DE-HDL packaged netlist, KiCad conversion of 04192023_DAF0TMB3IC0_F0TG_MB_C_brd_V02_OCP.brd

R6285  Q_RES  0 5% CHIP  pkg 0402LF  page 178 : A = USB_HUB2_TI_PWRCTL_POL ; B = USB_HUB2_TI_PWRCTL_POL_MRP_VBUS_DET
R4608  Q_RES  33.2 1% CHIP  pkg 0402LF  page 81 : A = GPU_FPGA_RST_R_N ; B = GPU_FPGA_RST_N

(kicad_pcb
	(version 20260206)
	(generator "pcbnew")
	(generator_version "10.0")
	(general
		(thickness 1.6)
		(legacy_teardrops no)
	)
	(paper "A4")
	(title_block
		(title "04192023_DAF0TMB3IC0_F0TG_MB_C_brd_V02_OCP.brd")
		(comment 1 "Grand Teton / footprints 508-509 of 8354")
	)
	(layers
		(0 "F.Cu" signal "TOP")
		(4 "In1.Cu" signal "GND")
		(6 "In2.Cu" signal "IN1")
		(8 "In3.Cu" signal "GND1")
		(10 "In4.Cu" signal "IN2")
		(12 "In5.Cu" signal "GND2")
		(14 "In6.Cu" signal "IN3")
		(16 "In7.Cu" signal "GND3")
		(18 "In8.Cu" signal "VCC")
		(20 "In9.Cu" signal "VCC1")
		(22 "In10.Cu" signal "GND4")
		(24 "In11.Cu" signal "IN4")
		(26 "In12.Cu" signal "GND5")
		(28 "In13.Cu" signal "IN5")
		(30 "In14.Cu" signal "GND6")
		(32 "In15.Cu" signal "IN6")
		(34 "In16.Cu" signal "GND7")
		(2 "B.Cu" signal "BOTTOM")
		(9 "F.Adhes" user "F.Adhesive")
		(11 "B.Adhes" user "B.Adhesive")
		(13 "F.Paste" user "Package Geometry/Pastemask Top")
		(15 "B.Paste" user "Package Geometry/Pastemask Bottom")
		(5 "F.SilkS" user "Ref Des/Silkscreen Top")
		(7 "B.SilkS" user "Ref Des/Silkscreen Bottom")
		(1 "F.Mask" user "Board Geometry/Soldermask Top")
		(3 "B.Mask" user "Board Geometry/Soldermask Bottom")
		(17 "Dwgs.User" user "User.Drawings")
		(19 "Cmts.User" user "User.Comments")
		(21 "Eco1.User" user "User.Eco1")
		(23 "Eco2.User" user "User.Eco2")
		(25 "Edge.Cuts" user "Board Geometry/Outline")
		(27 "Margin" user)
		(31 "F.CrtYd" user "Package Geometry/Place Bound Top")
		(29 "B.CrtYd" user "Package Geometry/Place Bound Bottom")
		(35 "F.Fab" user "Ref Des/Assembly Top")
		(33 "B.Fab" user "Ref Des/Assembly Bottom")
	)
	(footprint ""
		(layer "F.Cu")
		(at 113.283238 -39.40175 -90)
		(property "Reference" "R6285"
			(at 0 0 270)
			(layer "F.SilkS")
			(hide yes)
			(effects
				(font
					(size 1.27 1.27)
				)
			)
		)
		(property "Value" ""
			(at 0 0 270)
			(layer "F.Fab")
			(effects
				(font
					(size 1.27 1.27)
				)
			)
		)
		(duplicate_pad_numbers_are_jumpers no)
		(fp_line
			(start -0.7874 0.4064)
			(end -0.7874 -0.4064)
			(stroke
				(width 0.1524)
				(type default)
			)
			(layer "F.SilkS")
		)
		(fp_line
			(start 0.7874 0.4064)
			(end -0.7874 0.4064)
			(stroke
				(width 0.1524)
				(type default)
			)
			(layer "F.SilkS")
		)
		(fp_line
			(start -0.7874 -0.4064)
			(end 0.7874 -0.4064)
			(stroke
				(width 0.1524)
				(type default)
			)
			(layer "F.SilkS")
		)
		(fp_line
			(start 0.7874 -0.4064)
			(end 0.7874 0.4064)
			(stroke
				(width 0.1524)
				(type default)
			)
			(layer "F.SilkS")
		)
		(fp_line
			(start -0.67945 0.3048)
			(end -0.67945 -0.305054)
			(stroke
				(width 0.1)
				(type default)
			)
			(layer "F.Fab")
		)
		(fp_line
			(start -0.12065 0.3048)
			(end -0.67945 0.3048)
			(stroke
				(width 0.1)
				(type default)
			)
			(layer "F.Fab")
		)
		(fp_line
			(start 0.120396 0.3048)
			(end 0.120396 0.2794)
			(stroke
				(width 0.1)
				(type default)
			)
			(layer "F.Fab")
		)
		(fp_line
			(start 0.67945 0.3048)
			(end 0.120396 0.3048)
			(stroke
				(width 0.1)
				(type default)
			)
			(layer "F.Fab")
		)
		(fp_line
			(start -0.12065 0.2794)
			(end -0.12065 0.3048)
			(stroke
				(width 0.1)
				(type default)
			)
			(layer "F.Fab")
		)
		(fp_line
			(start 0.120396 0.2794)
			(end -0.12065 0.2794)
			(stroke
				(width 0.1)
				(type default)
			)
			(layer "F.Fab")
		)
		(fp_line
			(start -0.12065 -0.2794)
			(end 0.12065 -0.2794)
			(stroke
				(width 0.1)
				(type default)
			)
			(layer "F.Fab")
		)
		(fp_line
			(start 0.12065 -0.2794)
			(end 0.12065 -0.3048)
			(stroke
				(width 0.1)
				(type default)
			)
			(layer "F.Fab")
		)
		(fp_line
			(start 0.12065 -0.3048)
			(end 0.67945 -0.3048)
			(stroke
				(width 0.1)
				(type default)
			)
			(layer "F.Fab")
		)
		(fp_line
			(start 0.67945 -0.3048)
			(end 0.67945 0.3048)
			(stroke
				(width 0.1)
				(type default)
			)
			(layer "F.Fab")
		)
		(fp_line
			(start -0.67945 -0.305054)
			(end -0.12065 -0.305054)
			(stroke
				(width 0.1)
				(type default)
			)
			(layer "F.Fab")
		)
		(fp_line
			(start -0.12065 -0.305054)
			(end -0.12065 -0.2794)
			(stroke
				(width 0.1)
				(type default)
			)
			(layer "F.Fab")
		)
		(pad "1" smd circle
			(at -0.40005 0 270)
			(size 0 0)
			(layers "F.Cu" "F.Mask" "F.Paste")
			(net "USB_HUB2_TI_PWRCTL_POL")
		)
		(pad "2" smd circle
			(at 0.40005 0 270)
			(size 0 0)
			(layers "F.Cu" "F.Mask" "F.Paste")
			(net "USB_HUB2_TI_PWRCTL_POL_MRP_VBUS_DET")
		)
	)
	(footprint ""
		(layer "F.Cu")
		(at 208.894426 -114.249708 180)
		(property "Reference" "R4608"
			(at 0 0 180)
			(layer "F.SilkS")
			(hide yes)
			(effects
				(font
					(size 1.27 1.27)
				)
			)
		)
		(property "Value" ""
			(at 0 0 180)
			(layer "F.Fab")
			(effects
				(font
					(size 1.27 1.27)
				)
			)
		)
		(duplicate_pad_numbers_are_jumpers no)
		(fp_line
			(start 0.7874 0.4064)
			(end -0.7874 0.4064)
			(stroke
				(width 0.1524)
				(type default)
			)
			(layer "F.SilkS")
		)
		(fp_line
			(start 0.7874 -0.4064)
			(end 0.7874 0.4064)
			(stroke
				(width 0.1524)
				(type default)
			)
			(layer "F.SilkS")
		)
		(fp_line
			(start -0.7874 0.4064)
			(end -0.7874 -0.4064)
			(stroke
				(width 0.1524)
				(type default)
			)
			(layer "F.SilkS")
		)
		(fp_line
			(start -0.7874 -0.4064)
			(end 0.7874 -0.4064)
			(stroke
				(width 0.1524)
				(type default)
			)
			(layer "F.SilkS")
		)
		(fp_line
			(start 0.67945 0.3048)
			(end 0.120396 0.3048)
			(stroke
				(width 0.1)
				(type default)
			)
			(layer "F.Fab")
		)
		(fp_line
			(start 0.67945 -0.3048)
			(end 0.67945 0.3048)
			(stroke
				(width 0.1)
				(type default)
			)
			(layer "F.Fab")
		)
		(fp_line
			(start 0.12065 -0.2794)
			(end 0.12065 -0.3048)
			(stroke
				(width 0.1)
				(type default)
			)
			(layer "F.Fab")
		)
		(fp_line
			(start 0.12065 -0.3048)
			(end 0.67945 -0.3048)
			(stroke
				(width 0.1)
				(type default)
			)
			(layer "F.Fab")
		)
		(fp_line
			(start 0.120396 0.3048)
			(end 0.120396 0.2794)
			(stroke
				(width 0.1)
				(type default)
			)
			(layer "F.Fab")
		)
		(fp_line
			(start 0.120396 0.2794)
			(end -0.12065 0.2794)
			(stroke
				(width 0.1)
				(type default)
			)
			(layer "F.Fab")
		)
		(fp_line
			(start -0.12065 0.3048)
			(end -0.67945 0.3048)
			(stroke
				(width 0.1)
				(type default)
			)
			(layer "F.Fab")
		)
		(fp_line
			(start -0.12065 0.2794)
			(end -0.12065 0.3048)
			(stroke
				(width 0.1)
				(type default)
			)
			(layer "F.Fab")
		)
		(fp_line
			(start -0.12065 -0.2794)
			(end 0.12065 -0.2794)
			(stroke
				(width 0.1)
				(type default)
			)
			(layer "F.Fab")
		)
		(fp_line
			(start -0.12065 -0.305054)
			(end -0.12065 -0.2794)
			(stroke
				(width 0.1)
				(type default)
			)
			(layer "F.Fab")
		)
		(fp_line
			(start -0.67945 0.3048)
			(end -0.67945 -0.305054)
			(stroke
				(width 0.1)
				(type default)
			)
			(layer "F.Fab")
		)
		(fp_line
			(start -0.67945 -0.305054)
			(end -0.12065 -0.305054)
			(stroke
				(width 0.1)
				(type default)
			)
			(layer "F.Fab")
		)
		(pad "1" smd circle
			(at -0.40005 0 180)
			(size 0 0)
			(layers "F.Cu" "F.Mask" "F.Paste")
			(net "GPU_FPGA_RST_R_N")
		)
		(pad "2" smd circle
			(at 0.40005 0 180)
			(size 0 0)
			(layers "F.Cu" "F.Mask" "F.Paste")
			(net "GPU_FPGA_RST_N")
		)
	)
)
